(kicad_pcb
	(version 20260206)
	(generator "pcbnew")
	(generator_version "10.0")
	(general
		(thickness 1.6)
		(legacy_teardrops no)
	)
	(paper "A4")
	(title_block
		(title "9054_F0T_PDB_BD_GPU_F_V04_1213_1550_OCP.brd")
		(comment 1 "Grand Teton / footprints 299-303 of 608")
	)
	(layers
		(0 "F.Cu" signal "TOP")
		(4 "In1.Cu" signal "GND")
		(6 "In2.Cu" signal "IN1")
		(8 "In3.Cu" signal "GND1")
		(10 "In4.Cu" signal "VCC")
		(12 "In5.Cu" signal "VCC1")
		(14 "In6.Cu" signal "GND2")
		(16 "In7.Cu" signal "IN2")
		(18 "In8.Cu" signal "GND3")
		(2 "B.Cu" signal "BOTTOM")
		(9 "F.Adhes" user "F.Adhesive")
		(11 "B.Adhes" user "B.Adhesive")
		(13 "F.Paste" user "Package Geometry/Pastemask Top")
		(15 "B.Paste" user "Package Geometry/Pastemask Bottom")
		(5 "F.SilkS" user "Ref Des/Silkscreen Top")
		(7 "B.SilkS" user "Ref Des/Silkscreen Bottom")
		(1 "F.Mask" user "Board Geometry/Soldermask Top")
		(3 "B.Mask" user "Board Geometry/Soldermask Bottom")
		(17 "Dwgs.User" user "User.Drawings")
		(19 "Cmts.User" user "User.Comments")
		(21 "Eco1.User" user "User.Eco1")
		(23 "Eco2.User" user "User.Eco2")
		(25 "Edge.Cuts" user "Board Geometry/Outline")
		(27 "Margin" user)
		(31 "F.CrtYd" user "Package Geometry/Place Bound Top")
		(29 "B.CrtYd" user "Package Geometry/Place Bound Bottom")
		(35 "F.Fab" user "Ref Des/Assembly Top")
		(33 "B.Fab" user "Ref Des/Assembly Bottom")
	)
	(footprint ""
		(layer "F.Cu")
		(at 429.2854 -31.3436 -90)
		(property "Reference" "R57"
			(at 0 0 270)
			(layer "F.SilkS")
			(hide yes)
			(effects
				(font
					(size 1.27 1.27)
				)
			)
		)
		(property "Value" ""
			(at 0 0 270)
			(layer "F.Fab")
			(effects
				(font
					(size 1.27 1.27)
				)
			)
		)
		(duplicate_pad_numbers_are_jumpers no)
		(fp_line
			(start -0.7874 0.4064)
			(end -0.7874 -0.4064)
			(stroke
				(width 0.1524)
				(type default)
			)
			(layer "F.SilkS")
		)
		(fp_line
			(start 0.7874 0.4064)
			(end -0.7874 0.4064)
			(stroke
				(width 0.1524)
				(type default)
			)
			(layer "F.SilkS")
		)
		(fp_line
			(start -0.7874 -0.4064)
			(end 0.7874 -0.4064)
			(stroke
				(width 0.1524)
				(type default)
			)
			(layer "F.SilkS")
		)
		(fp_line
			(start 0.7874 -0.4064)
			(end 0.7874 0.4064)
			(stroke
				(width 0.1524)
				(type default)
			)
			(layer "F.SilkS")
		)
		(fp_line
			(start -0.67945 0.3048)
			(end -0.67945 -0.305054)
			(stroke
				(width 0.1)
				(type default)
			)
			(layer "F.Fab")
		)
		(fp_line
			(start -0.12065 0.3048)
			(end -0.67945 0.3048)
			(stroke
				(width 0.1)
				(type default)
			)
			(layer "F.Fab")
		)
		(fp_line
			(start 0.120396 0.3048)
			(end 0.120396 0.2794)
			(stroke
				(width 0.1)
				(type default)
			)
			(layer "F.Fab")
		)
		(fp_line
			(start 0.67945 0.3048)
			(end 0.120396 0.3048)
			(stroke
				(width 0.1)
				(type default)
			)
			(layer "F.Fab")
		)
		(fp_line
			(start -0.12065 0.2794)
			(end -0.12065 0.3048)
			(stroke
				(width 0.1)
				(type default)
			)
			(layer "F.Fab")
		)
		(fp_line
			(start 0.120396 0.2794)
			(end -0.12065 0.2794)
			(stroke
				(width 0.1)
				(type default)
			)
			(layer "F.Fab")
		)
		(fp_line
			(start -0.12065 -0.2794)
			(end 0.12065 -0.2794)
			(stroke
				(width 0.1)
				(type default)
			)
			(layer "F.Fab")
		)
		(fp_line
			(start 0.12065 -0.2794)
			(end 0.12065 -0.3048)
			(stroke
				(width 0.1)
				(type default)
			)
			(layer "F.Fab")
		)
		(fp_line
			(start 0.12065 -0.3048)
			(end 0.67945 -0.3048)
			(stroke
				(width 0.1)
				(type default)
			)
			(layer "F.Fab")
		)
		(fp_line
			(start 0.67945 -0.3048)
			(end 0.67945 0.3048)
			(stroke
				(width 0.1)
				(type default)
			)
			(layer "F.Fab")
		)
		(fp_line
			(start -0.67945 -0.305054)
			(end -0.12065 -0.305054)
			(stroke
				(width 0.1)
				(type default)
			)
			(layer "F.Fab")
		)
		(fp_line
			(start -0.12065 -0.305054)
			(end -0.12065 -0.2794)
			(stroke
				(width 0.1)
				(type default)
			)
			(layer "F.Fab")
		)
		(pad "1" smd circle
			(at -0.40005 0 270)
			(size 0 0)
			(layers "F.Cu" "F.Mask" "F.Paste")
			(net "P3V3_AUX")
		)
		(pad "2" smd circle
			(at 0.40005 0 270)
			(size 0 0)
			(layers "F.Cu" "F.Mask" "F.Paste")
			(net "FRU_WP_N")
		)
	)
	(footprint ""
		(layer "F.Cu")
		(at 143.003778 -29.5402 180)
		(property "Reference" "PR6989"
			(at 0.458978 -4.68757 0)
			(unlocked yes)
			(layer "F.SilkS")
			(effects
				(font
					(size 0.7874 0.5842)
					(thickness 0.1524)
				)
				(justify left)
			)
		)
		(property "Value" ""
			(at 0 0 180)
			(layer "F.Fab")
			(effects
				(font
					(size 1.27 1.27)
				)
			)
		)
		(duplicate_pad_numbers_are_jumpers no)
		(fp_line
			(start 3.9878 3.5814)
			(end -3.9878 3.5814)
			(stroke
				(width 0.1524)
				(type default)
			)
			(layer "F.SilkS")
		)
		(fp_line
			(start 3.9878 -3.5814)
			(end 3.9878 3.5814)
			(stroke
				(width 0.1524)
				(type default)
			)
			(layer "F.SilkS")
		)
		(fp_line
			(start -3.9878 3.5814)
			(end -3.9878 -3.5814)
			(stroke
				(width 0.1524)
				(type default)
			)
			(layer "F.SilkS")
		)
		(fp_line
			(start -3.9878 -3.5814)
			(end 3.9878 -3.5814)
			(stroke
				(width 0.1524)
				(type default)
			)
			(layer "F.SilkS")
		)
		(fp_line
			(start 3.5306 3.353054)
			(end -3.5306 3.353054)
			(stroke
				(width 0.1)
				(type default)
			)
			(layer "F.Fab")
		)
		(fp_line
			(start 3.5306 -3.353054)
			(end 3.5306 3.353054)
			(stroke
				(width 0.1)
				(type default)
			)
			(layer "F.Fab")
		)
		(fp_line
			(start -3.5306 3.353054)
			(end -3.5306 -3.353054)
			(stroke
				(width 0.1)
				(type default)
			)
			(layer "F.Fab")
		)
		(fp_line
			(start -3.5306 -3.353054)
			(end 3.5306 -3.353054)
			(stroke
				(width 0.1)
				(type default)
			)
			(layer "F.Fab")
		)
		(pad "1A" smd rect
			(at -2.249932 0)
			(size 3.2004 6.858)
			(layers "F.Cu" "F.Mask" "F.Paste")
			(net "P52V_2")
		)
		(pad "1B" smd rect
			(at -0.776732 0 180)
			(size 0.254 0.508)
			(layers "F.Cu" "F.Mask" "F.Paste")
			(net "P52V_HS2_SENSE_P_R2")
		)
		(pad "2A" smd rect
			(at 2.249932 0)
			(size 3.2004 6.858)
			(layers "F.Cu" "F.Mask" "F.Paste")
			(net "P52V_HS2_DRAIN_2")
		)
		(pad "2B" smd rect
			(at 0.776732 0 180)
			(size 0.254 0.508)
			(layers "F.Cu" "F.Mask" "F.Paste")
			(net "P52V_HS2_SENSE_N_R2")
		)
	)
	(footprint ""
		(layer "F.Cu")
		(at 420.37 -42.418)
		(property "Reference" "U8"
			(at -1.905 -4.79933 0)
			(unlocked yes)
			(layer "F.SilkS")
			(effects
				(font
					(size 0.7874 0.5842)
					(thickness 0.1524)
				)
				(justify left)
			)
		)
		(property "Value" ""
			(at 0 0 0)
			(layer "F.Fab")
			(effects
				(font
					(size 1.27 1.27)
				)
			)
		)
		(duplicate_pad_numbers_are_jumpers no)
		(fp_line
			(start -2.0066 -3.9624)
			(end -0.5842 -3.9624)
			(stroke
				(width 0.1524)
				(type default)
			)
			(layer "F.SilkS")
		)
		(fp_line
			(start -2.0066 3.9624)
			(end -2.0066 -3.9624)
			(stroke
				(width 0.1524)
				(type default)
			)
			(layer "F.SilkS")
		)
		(fp_line
			(start -0.5842 -3.9624)
			(end 0 -3.3782)
			(stroke
				(width 0.1524)
				(type default)
			)
			(layer "F.SilkS")
		)
		(fp_line
			(start 0 -3.3782)
			(end 0.5842 -3.9624)
			(stroke
				(width 0.1524)
				(type default)
			)
			(layer "F.SilkS")
		)
		(fp_line
			(start 0.5842 -3.9624)
			(end 2.0066 -3.9624)
			(stroke
				(width 0.1524)
				(type default)
			)
			(layer "F.SilkS")
		)
		(fp_line
			(start 2.0066 -3.9624)
			(end 2.0066 3.9624)
			(stroke
				(width 0.1524)
				(type default)
			)
			(layer "F.SilkS")
		)
		(fp_line
			(start 2.0066 3.9624)
			(end -2.0066 3.9624)
			(stroke
				(width 0.1524)
				(type default)
			)
			(layer "F.SilkS")
		)
		(fp_poly
			(pts
				(xy -3.007614 -3.9116) (xy -3.388614 -4.6736) (xy -2.626614 -4.6736)
			)
			(stroke
				(width 0)
				(type default)
			)
			(fill yes)
			(layer "F.SilkS")
		)
		(fp_line
			(start -3.724402 -3.80365)
			(end -3.724402 3.80365)
			(stroke
				(width 0.1)
				(type default)
			)
			(layer "F.Fab")
		)
		(fp_line
			(start -3.724402 3.80365)
			(end -2.2479 3.80365)
			(stroke
				(width 0.1)
				(type default)
			)
			(layer "F.Fab")
		)
		(fp_line
			(start -3.7211 -3.34645)
			(end -3.7211 -3.80365)
			(stroke
				(width 0.1)
				(type default)
			)
			(layer "F.Fab")
		)
		(fp_line
			(start -2.2479 -3.974846)
			(end -2.2479 -3.80365)
			(stroke
				(width 0.1)
				(type default)
			)
			(layer "F.Fab")
		)
		(fp_line
			(start -2.2479 -3.80365)
			(end -3.724402 -3.80365)
			(stroke
				(width 0.1)
				(type default)
			)
			(layer "F.Fab")
		)
		(fp_line
			(start -2.2479 3.80365)
			(end -2.2479 3.9624)
			(stroke
				(width 0.1)
				(type default)
			)
			(layer "F.Fab")
		)
		(fp_line
			(start -2.2479 3.9624)
			(end 2.2479 3.9624)
			(stroke
				(width 0.1)
				(type default)
			)
			(layer "F.Fab")
		)
		(fp_line
			(start 2.2479 -3.974846)
			(end -2.2479 -3.974846)
			(stroke
				(width 0.1)
				(type default)
			)
			(layer "F.Fab")
		)
		(fp_line
			(start 2.2479 -3.80365)
			(end 2.2479 -3.974846)
			(stroke
				(width 0.1)
				(type default)
			)
			(layer "F.Fab")
		)
		(fp_line
			(start 2.2479 3.80365)
			(end 3.7211 3.80365)
			(stroke
				(width 0.1)
				(type default)
			)
			(layer "F.Fab")
		)
		(fp_line
			(start 2.2479 3.9624)
			(end 2.2479 3.80365)
			(stroke
				(width 0.1)
				(type default)
			)
			(layer "F.Fab")
		)
		(fp_line
			(start 3.7211 -3.80365)
			(end 2.2479 -3.80365)
			(stroke
				(width 0.1)
				(type default)
			)
			(layer "F.Fab")
		)
		(fp_line
			(start 3.7211 3.80365)
			(end 3.7211 -3.80365)
			(stroke
				(width 0.1)
				(type default)
			)
			(layer "F.Fab")
		)
		(fp_poly
			(pts
				(xy -3.8862 -3.570986) (xy -4.6482 -3.189986) (xy -4.6482 -3.951986)
			)
			(stroke
				(width 0)
				(type default)
			)
			(fill yes)
			(layer "F.Fab")
		)
		(pad "1" smd rect
			(at -2.921 -3.57505 270)
			(size 0.3556 1.4986)
			(layers "F.Cu" "F.Mask" "F.Paste")
			(net "PU_U8_PIN1")
		)
		(pad "2" smd rect
			(at -2.921 -2.925064 270)
			(size 0.3556 1.4986)
			(layers "F.Cu" "F.Mask" "F.Paste")
			(net "PCA9555_A1")
		)
		(pad "3" smd rect
			(at -2.921 -2.275078 270)
			(size 0.3556 1.4986)
			(layers "F.Cu" "F.Mask" "F.Paste")
			(net "PCA9555_A2")
		)
		(pad "4" smd rect
			(at -2.921 -1.625092 270)
			(size 0.3556 1.4986)
			(layers "F.Cu" "F.Mask" "F.Paste")
			(net "P52V_HS1_FLT")
		)
		(pad "5" smd rect
			(at -2.921 -0.975106 270)
			(size 0.3556 1.4986)
			(layers "F.Cu" "F.Mask" "F.Paste")
			(net "P52V_HS2_FLT")
		)
		(pad "6" smd rect
			(at -2.921 -0.32512 270)
			(size 0.3556 1.4986)
			(layers "F.Cu" "F.Mask" "F.Paste")
			(net "PRSNT_FAN_BP0_N")
		)
		(pad "7" smd rect
			(at -2.921 0.32512 270)
			(size 0.3556 1.4986)
			(layers "F.Cu" "F.Mask" "F.Paste")
			(net "PRSNT_FAN_BP1_N")
		)
		(pad "8" smd rect
			(at -2.921 0.975106 270)
			(size 0.3556 1.4986)
			(layers "F.Cu" "F.Mask" "F.Paste")
			(net "TP_U8_P04")
		)
		(pad "9" smd rect
			(at -2.921 1.625092 270)
			(size 0.3556 1.4986)
			(layers "F.Cu" "F.Mask" "F.Paste")
			(net "TP_U8_P05")
		)
		(pad "10" smd rect
			(at -2.921 2.275078 270)
			(size 0.3556 1.4986)
			(layers "F.Cu" "F.Mask" "F.Paste")
			(net "TP_U8_P06")
		)
		(pad "11" smd rect
			(at -2.921 2.925064 270)
			(size 0.3556 1.4986)
			(layers "F.Cu" "F.Mask" "F.Paste")
			(net "TP_U8_P07")
		)
		(pad "12" smd rect
			(at -2.921 3.57505 270)
			(size 0.3556 1.4986)
			(layers "F.Cu" "F.Mask" "F.Paste")
			(net "GND")
		)
		(pad "13" smd rect
			(at 2.921 3.57505 270)
			(size 0.3556 1.4986)
			(layers "F.Cu" "F.Mask" "F.Paste")
			(net "PWRGD_P52V_HS1_PG")
		)
		(pad "14" smd rect
			(at 2.921 2.925064 270)
			(size 0.3556 1.4986)
			(layers "F.Cu" "F.Mask" "F.Paste")
			(net "PWRGD_P52V_HS2_PG")
		)
		(pad "15" smd rect
			(at 2.921 2.275078 270)
			(size 0.3556 1.4986)
			(layers "F.Cu" "F.Mask" "F.Paste")
			(net "BOARD_ID_0")
		)
		(pad "16" smd rect
			(at 2.921 1.625092 270)
			(size 0.3556 1.4986)
			(layers "F.Cu" "F.Mask" "F.Paste")
			(net "BOARD_ID_1")
		)
		(pad "17" smd rect
			(at 2.921 0.975106 270)
			(size 0.3556 1.4986)
			(layers "F.Cu" "F.Mask" "F.Paste")
			(net "BOARD_ID_2")
		)
		(pad "18" smd rect
			(at 2.921 0.32512 270)
			(size 0.3556 1.4986)
			(layers "F.Cu" "F.Mask" "F.Paste")
			(net "SKU_ID_0")
		)
		(pad "19" smd rect
			(at 2.921 -0.32512 270)
			(size 0.3556 1.4986)
			(layers "F.Cu" "F.Mask" "F.Paste")
			(net "SKU_ID_1")
		)
		(pad "20" smd rect
			(at 2.921 -0.975106 270)
			(size 0.3556 1.4986)
			(layers "F.Cu" "F.Mask" "F.Paste")
			(net "SKU_ID_2")
		)
		(pad "21" smd rect
			(at 2.921 -1.625092 270)
			(size 0.3556 1.4986)
			(layers "F.Cu" "F.Mask" "F.Paste")
			(net "PCA9555_A0")
		)
		(pad "22" smd rect
			(at 2.921 -2.275078 270)
			(size 0.3556 1.4986)
			(layers "F.Cu" "F.Mask" "F.Paste")
			(net "SMB_IOEXP_SCL")
		)
		(pad "23" smd rect
			(at 2.921 -2.925064 270)
			(size 0.3556 1.4986)
			(layers "F.Cu" "F.Mask" "F.Paste")
			(net "SMB_IOEXP_SDA")
		)
		(pad "24" smd rect
			(at 2.921 -3.57505 270)
			(size 0.3556 1.4986)
			(layers "F.Cu" "F.Mask" "F.Paste")
			(net "P3V3_AUX")
		)
	)
	(footprint ""
		(layer "F.Cu")
		(at 447.421 -44.196)
		(property "Reference" "R382"
			(at 0 0 0)
			(layer "F.SilkS")
			(hide yes)
			(effects
				(font
					(size 1.27 1.27)
				)
			)
		)
		(property "Value" ""
			(at 0 0 0)
			(layer "F.Fab")
			(effects
				(font
					(size 1.27 1.27)
				)
			)
		)
		(duplicate_pad_numbers_are_jumpers no)
		(fp_line
			(start -0.7874 -0.4064)
			(end 0.7874 -0.4064)
			(stroke
				(width 0.1524)
				(type default)
			)
			(layer "F.SilkS")
		)
		(fp_line
			(start -0.7874 0.4064)
			(end -0.7874 -0.4064)
			(stroke
				(width 0.1524)
				(type default)
			)
			(layer "F.SilkS")
		)
		(fp_line
			(start 0.7874 -0.4064)
			(end 0.7874 0.4064)
			(stroke
				(width 0.1524)
				(type default)
			)
			(layer "F.SilkS")
		)
		(fp_line
			(start 0.7874 0.4064)
			(end -0.7874 0.4064)
			(stroke
				(width 0.1524)
				(type default)
			)
			(layer "F.SilkS")
		)
		(fp_line
			(start -0.67945 -0.305054)
			(end -0.12065 -0.305054)
			(stroke
				(width 0.1)
				(type default)
			)
			(layer "F.Fab")
		)
		(fp_line
			(start -0.67945 0.3048)
			(end -0.67945 -0.305054)
			(stroke
				(width 0.1)
				(type default)
			)
			(layer "F.Fab")
		)
		(fp_line
			(start -0.12065 -0.305054)
			(end -0.12065 -0.2794)
			(stroke
				(width 0.1)
				(type default)
			)
			(layer "F.Fab")
		)
		(fp_line
			(start -0.12065 -0.2794)
			(end 0.12065 -0.2794)
			(stroke
				(width 0.1)
				(type default)
			)
			(layer "F.Fab")
		)
		(fp_line
			(start -0.12065 0.2794)
			(end -0.12065 0.3048)
			(stroke
				(width 0.1)
				(type default)
			)
			(layer "F.Fab")
		)
		(fp_line
			(start -0.12065 0.3048)
			(end -0.67945 0.3048)
			(stroke
				(width 0.1)
				(type default)
			)
			(layer "F.Fab")
		)
		(fp_line
			(start 0.120396 0.2794)
			(end -0.12065 0.2794)
			(stroke
				(width 0.1)
				(type default)
			)
			(layer "F.Fab")
		)
		(fp_line
			(start 0.120396 0.3048)
			(end 0.120396 0.2794)
			(stroke
				(width 0.1)
				(type default)
			)
			(layer "F.Fab")
		)
		(fp_line
			(start 0.12065 -0.3048)
			(end 0.67945 -0.3048)
			(stroke
				(width 0.1)
				(type default)
			)
			(layer "F.Fab")
		)
		(fp_line
			(start 0.12065 -0.2794)
			(end 0.12065 -0.3048)
			(stroke
				(width 0.1)
				(type default)
			)
			(layer "F.Fab")
		)
		(fp_line
			(start 0.67945 -0.3048)
			(end 0.67945 0.3048)
			(stroke
				(width 0.1)
				(type default)
			)
			(layer "F.Fab")
		)
		(fp_line
			(start 0.67945 0.3048)
			(end 0.120396 0.3048)
			(stroke
				(width 0.1)
				(type default)
			)
			(layer "F.Fab")
		)
		(pad "1" smd circle
			(at -0.40005 0)
			(size 0 0)
			(layers "F.Cu" "F.Mask" "F.Paste")
			(net "GPU_HSC_BUF_R_EN")
		)
		(pad "2" smd circle
			(at 0.40005 0)
			(size 0 0)
			(layers "F.Cu" "F.Mask" "F.Paste")
			(net "GPU_HSC_BUF_EN")
		)
	)
	(footprint ""
		(layer "F.Cu")
		(at 112.988852 -44.0944 -90)
		(property "Reference" "PR6973"
			(at 0 0 270)
			(layer "F.SilkS")
			(hide yes)
			(effects
				(font
					(size 1.27 1.27)
				)
			)
		)
		(property "Value" ""
			(at 0 0 270)
			(layer "F.Fab")
			(effects
				(font
					(size 1.27 1.27)
				)
			)
		)
		(duplicate_pad_numbers_are_jumpers no)
		(fp_line
			(start -1.2954 0.5842)
			(end -1.2954 -0.5842)
			(stroke
				(width 0.1524)
				(type default)
			)
			(layer "F.SilkS")
		)
		(fp_line
			(start 1.2954 0.5842)
			(end -1.2954 0.5842)
			(stroke
				(width 0.1524)
				(type default)
			)
			(layer "F.SilkS")
		)
		(fp_line
			(start -1.2954 -0.5842)
			(end 1.2954 -0.5842)
			(stroke
				(width 0.1524)
				(type default)
			)
			(layer "F.SilkS")
		)
		(fp_line
			(start 1.2954 -0.5842)
			(end 1.2954 0.5842)
			(stroke
				(width 0.1524)
				(type default)
			)
			(layer "F.SilkS")
		)
		(fp_line
			(start -0.8636 0.4572)
			(end -0.8636 0.4318)
			(stroke
				(width 0.1)
				(type default)
			)
			(layer "F.Fab")
		)
		(fp_line
			(start 0.8636 0.4572)
			(end -0.8636 0.4572)
			(stroke
				(width 0.1)
				(type default)
			)
			(layer "F.Fab")
		)
		(fp_line
			(start -0.8636 0.4318)
			(end -0.8636 0.4064)
			(stroke
				(width 0.1)
				(type default)
			)
			(layer "F.Fab")
		)
		(fp_line
			(start -1.1938 0.4064)
			(end -1.1938 -0.406654)
			(stroke
				(width 0.1)
				(type default)
			)
			(layer "F.Fab")
		)
		(fp_line
			(start -0.8636 0.4064)
			(end -1.1938 0.4064)
			(stroke
				(width 0.1)
				(type default)
			)
			(layer "F.Fab")
		)
		(fp_line
			(start 0.8636 0.4064)
			(end 0.8636 0.4572)
			(stroke
				(width 0.1)
				(type default)
			)
			(layer "F.Fab")
		)
		(fp_line
			(start 1.1938 0.4064)
			(end 0.8636 0.4064)
			(stroke
				(width 0.1)
				(type default)
			)
			(layer "F.Fab")
		)
		(fp_line
			(start -1.1938 -0.406654)
			(end -0.8636 -0.406654)
			(stroke
				(width 0.1)
				(type default)
			)
			(layer "F.Fab")
		)
		(fp_line
			(start -0.8636 -0.406654)
			(end -0.8636 -0.4572)
			(stroke
				(width 0.1)
				(type default)
			)
			(layer "F.Fab")
		)
		(fp_line
			(start 0.8636 -0.406654)
			(end 1.1938 -0.406654)
			(stroke
				(width 0.1)
				(type default)
			)
			(layer "F.Fab")
		)
		(fp_line
			(start 1.1938 -0.406654)
			(end 1.1938 0.4064)
			(stroke
				(width 0.1)
				(type default)
			)
			(layer "F.Fab")
		)
		(fp_line
			(start -0.8636 -0.4572)
			(end 0.8636 -0.4572)
			(stroke
				(width 0.1)
				(type default)
			)
			(layer "F.Fab")
		)
		(fp_line
			(start 0.8636 -0.4572)
			(end 0.8636 -0.406654)
			(stroke
				(width 0.1)
				(type default)
			)
			(layer "F.Fab")
		)
		(pad "1" smd rect
			(at -0.7366 0 180)
			(size 0.7112 0.8128)
			(layers "F.Cu" "F.Mask" "F.Paste")
			(net "P52V_HS2_GATE2_R")
		)
		(pad "2" smd rect
			(at 0.7366 0 180)
			(size 0.7112 0.8128)
			(layers "F.Cu" "F.Mask" "F.Paste")
			(net "P52V_HS2_GATE4")
		)
	)
)
